(kicad_pcb
	(version 20241229)
	(generator "pcbnew")
	(generator_version "9.0")
	(general
		(thickness 1.294)
		(legacy_teardrops no)
	)
	(paper "A3")
	(title_block
		(title "Kintex 410T devboard")
		(date "2024-04-03")
		(rev "1.1.2")
		(comment 9 "footprints 330-332 of 975")
	)
	(layers
		(0 "F.Cu" mixed)
		(4 "In1.Cu" power)
		(6 "In2.Cu" power)
		(8 "In3.Cu" mixed)
		(10 "In4.Cu" power)
		(12 "In5.Cu" mixed)
		(14 "In6.Cu" power)
		(16 "In7.Cu" mixed)
		(18 "In8.Cu" power)
		(2 "B.Cu" mixed)
		(9 "F.Adhes" user "F.Adhesive")
		(11 "B.Adhes" user "B.Adhesive")
		(13 "F.Paste" user)
		(15 "B.Paste" user)
		(5 "F.SilkS" user "F.Silkscreen")
		(7 "B.SilkS" user "B.Silkscreen")
		(1 "F.Mask" user)
		(3 "B.Mask" user)
		(17 "Dwgs.User" user "User.Drawings")
		(19 "Cmts.User" user "User.Comments")
		(21 "Eco1.User" user "User.Eco1")
		(23 "Eco2.User" user "User.Eco2")
		(25 "Edge.Cuts" user)
		(27 "Margin" user)
		(31 "F.CrtYd" user "F.Courtyard")
		(29 "B.CrtYd" user "B.Courtyard")
		(35 "F.Fab" user)
		(33 "B.Fab" user)
	)
	(footprint "antmicro-footprints:BarrelJack_Pin2mm_MJ-179PH"
		(locked yes)
		(layer "F.Cu")
		(at 258.44 177.32)
		(property "Reference" "J2"
			(at -0.01 -6.28 0)
			(layer "F.SilkS")
			(effects
				(font
					(size 0.7 0.7)
					(thickness 0.15)
				)
				(justify left bottom)
			)
		)
		(property "Value" "BarrelJack_Pin2mm_MJ-179PH"
			(at 0 6.1 0)
			(layer "F.Fab")
			(effects
				(font
					(size 0.7 0.7)
					(thickness 0.15)
				)
				(justify left bottom)
			)
		)
		(property "Description" "DC Power Connector, Jack, 4 A, 1.95 mm, PCB Mount, Through Hole"
			(at 0 0 0)
			(layer "F.Fab")
			(hide yes)
			(effects
				(font
					(size 1.27 1.27)
					(thickness 0.15)
				)
			)
		)
		(property "Author" "Antmicro"
			(at 0 0 0)
			(layer "F.Fab")
			(hide yes)
			(effects
				(font
					(size 1 1)
					(thickness 0.15)
				)
			)
		)
		(property "License" "Apache-2.0"
			(at 0 0 0)
			(layer "F.Fab")
			(hide yes)
			(effects
				(font
					(size 1 1)
					(thickness 0.15)
				)
			)
		)
		(property "MPN" "MJ-179PH"
			(at 0 0 0)
			(layer "F.Fab")
			(hide yes)
			(effects
				(font
					(size 1 1)
					(thickness 0.15)
				)
			)
		)
		(property "Manufacturer" "Multicomp Pro"
			(at 0 0 0)
			(layer "F.Fab")
			(hide yes)
			(effects
				(font
					(size 1 1)
					(thickness 0.15)
				)
			)
		)
		(sheetname "Power supply")
		(sheetfile "power-supply.kicad_sch")
		(attr through_hole)
		(fp_line
			(start -0.1 -4.8)
			(end 0.8255 -4.8)
			(stroke
				(width 0.15)
				(type solid)
			)
			(layer "F.SilkS")
		)
		(fp_line
			(start -0.1 -2.4)
			(end -0.1 -4.8)
			(stroke
				(width 0.15)
				(type solid)
			)
			(layer "F.SilkS")
		)
		(fp_line
			(start -0.1 4.8)
			(end -0.1 2.4)
			(stroke
				(width 0.15)
				(type solid)
			)
			(layer "F.SilkS")
		)
		(fp_line
			(start 10.1 4.8)
			(end 10.1 -4.8)
			(stroke
				(width 0.15)
				(type solid)
			)
			(layer "F.SilkS")
		)
		(fp_line
			(start 14 -4.8)
			(end 5.1 -4.8)
			(stroke
				(width 0.15)
				(type solid)
			)
			(layer "F.SilkS")
		)
		(fp_line
			(start 14 4.8)
			(end -0.1 4.8)
			(stroke
				(width 0.15)
				(type solid)
			)
			(layer "F.SilkS")
		)
		(fp_line
			(start 14 4.8)
			(end 14 -4.8)
			(stroke
				(width 0.15)
				(type solid)
			)
			(layer "F.SilkS")
		)
		(fp_line
			(start -1.3 -2.5)
			(end -1.3 2.5)
			(stroke
				(width 0.05)
				(type solid)
			)
			(layer "F.CrtYd")
		)
		(fp_line
			(start -1.3 2.5)
			(end -0.4 2.5)
			(stroke
				(width 0.05)
				(type solid)
			)
			(layer "F.CrtYd")
		)
		(fp_line
			(start -0.4 -5.1)
			(end -0.4 -2.5)
			(stroke
				(width 0.05)
				(type solid)
			)
			(layer "F.CrtYd")
		)
		(fp_line
			(start -0.4 -2.5)
			(end -1.3 -2.5)
			(stroke
				(width 0.05)
				(type solid)
			)
			(layer "F.CrtYd")
		)
		(fp_line
			(start -0.4 2.5)
			(end -0.4 5.1)
			(stroke
				(width 0.05)
				(type solid)
			)
			(layer "F.CrtYd")
		)
		(fp_line
			(start -0.4 5.1)
			(end 14.3 5.1)
			(stroke
				(width 0.05)
				(type solid)
			)
			(layer "F.CrtYd")
		)
		(fp_line
			(start 0.7 -6.1)
			(end 0.7 -5.1)
			(stroke
				(width 0.05)
				(type solid)
			)
			(layer "F.CrtYd")
		)
		(fp_line
			(start 0.7 -5.1)
			(end -0.4 -5.1)
			(stroke
				(width 0.05)
				(type solid)
			)
			(layer "F.CrtYd")
		)
		(fp_line
			(start 5.2 -6.1)
			(end 0.7 -6.1)
			(stroke
				(width 0.05)
				(type solid)
			)
			(layer "F.CrtYd")
		)
		(fp_line
			(start 5.2 -5.1)
			(end 5.2 -6.1)
			(stroke
				(width 0.05)
				(type solid)
			)
			(layer "F.CrtYd")
		)
		(fp_line
			(start 14.3 -5.1)
			(end 5.2 -5.1)
			(stroke
				(width 0.05)
				(type solid)
			)
			(layer "F.CrtYd")
		)
		(fp_line
			(start 14.3 5.1)
			(end 14.3 -5.1)
			(stroke
				(width 0.05)
				(type solid)
			)
			(layer "F.CrtYd")
		)
		(fp_line
			(start -0.4 3.6)
			(end 0.5 4.5)
			(stroke
				(width 0.15)
				(type solid)
			)
			(layer "F.Fab")
		)
		(fp_rect
			(start -0.4 4.5)
			(end 13.7 -5.111)
			(stroke
				(width 0.15)
				(type solid)
			)
			(fill no)
			(layer "F.Fab")
		)
		(pad "1" thru_hole oval
			(at 0 0)
			(size 2 4.5)
			(drill oval 1 3.5)
			(layers "*.Cu" "*.Mask")
			(remove_unused_layers no)
			(net 1192 "Net-(F1-Pad1)")
			(pinfunction "1")
			(pintype "passive")
		)
		(pad "2" thru_hole oval
			(at 2.948 -4.879 270)
			(size 1.99 4)
			(drill oval 1 3)
			(layers "*.Cu" "*.Mask")
			(remove_unused_layers no)
			(net 1 "GND")
			(pinfunction "2")
			(pintype "passive")
		)
		(pad "3" thru_hole oval
			(at 5.999 0 180)
			(size 2 4)
			(drill oval 1 3)
			(layers "*.Cu" "*.Mask")
			(remove_unused_layers no)
			(net 1 "GND")
			(pinfunction "3")
			(pintype "passive")
		)
	)
	(footprint "antmicro-footprints:C_0402_1005Metric"
		(layer "F.Cu")
		(at 238.6 140.2)
		(descr "Capacitor SMD 0402")
		(tags "capacitor SMD 0402")
		(property "Reference" "C250"
			(at 1.55 2.25 0)
			(layer "F.SilkS")
			(effects
				(font
					(size 0.7 0.7)
					(thickness 0.15)
				)
				(justify left bottom)
			)
		)
		(property "Value" "C_100n_0402"
			(at 0 1.169 0)
			(layer "F.Fab")
			(effects
				(font
					(size 0.7 0.7)
					(thickness 0.15)
				)
				(justify left bottom)
			)
		)
		(property "Description" "SMD Multilayer Ceramic Capacitor, 0.1 µF, 50 V, 0402 [1005 Metric], ± 10%, X5R, GRM Series"
			(at 0 0 0)
			(layer "F.Fab")
			(hide yes)
			(effects
				(font
					(size 1.27 1.27)
					(thickness 0.15)
				)
			)
		)
		(property "Author" "Antmicro"
			(at 0 0 0)
			(layer "F.Fab")
			(hide yes)
			(effects
				(font
					(size 1 1)
					(thickness 0.15)
				)
			)
		)
		(property "Dielectric" "X5R"
			(at 0 0 0)
			(layer "F.Fab")
			(hide yes)
			(effects
				(font
					(size 1 1)
					(thickness 0.15)
				)
			)
		)
		(property "License" "Apache-2.0"
			(at 0 0 0)
			(layer "F.Fab")
			(hide yes)
			(effects
				(font
					(size 1 1)
					(thickness 0.15)
				)
			)
		)
		(property "MPN" "GRM155R61H104KE14D"
			(at 0 0 0)
			(layer "F.Fab")
			(hide yes)
			(effects
				(font
					(size 1 1)
					(thickness 0.15)
				)
			)
		)
		(property "Manufacturer" "Murata"
			(at 0 0 0)
			(layer "F.Fab")
			(hide yes)
			(effects
				(font
					(size 1 1)
					(thickness 0.15)
				)
			)
		)
		(property "Val" "100n"
			(at 0 0 0)
			(layer "F.Fab")
			(hide yes)
			(effects
				(font
					(size 1 1)
					(thickness 0.15)
				)
			)
		)
		(property "Voltage" "50V"
			(at 0 0 0)
			(layer "F.Fab")
			(hide yes)
			(effects
				(font
					(size 1 1)
					(thickness 0.15)
				)
			)
		)
		(sheetname "USB PHY")
		(sheetfile "usb-phy.kicad_sch")
		(attr smd)
		(fp_rect
			(start -0.925 -0.47)
			(end 0.925 0.47)
			(stroke
				(width 0.05)
				(type default)
			)
			(fill no)
			(layer "F.CrtYd")
		)
		(fp_line
			(start -0.494 -0.25)
			(end 0.504 -0.25)
			(stroke
				(width 0.15)
				(type solid)
			)
			(layer "F.Fab")
		)
		(fp_line
			(start -0.494 0.248)
			(end -0.494 -0.25)
			(stroke
				(width 0.15)
				(type solid)
			)
			(layer "F.Fab")
		)
		(fp_line
			(start 0.504 -0.25)
			(end 0.504 0.248)
			(stroke
				(width 0.15)
				(type solid)
			)
			(layer "F.Fab")
		)
		(fp_line
			(start 0.504 0.248)
			(end -0.494 0.248)
			(stroke
				(width 0.15)
				(type solid)
			)
			(layer "F.Fab")
		)
		(pad "1" smd roundrect
			(at -0.48 0)
			(size 0.59 0.64)
			(layers "F.Cu" "F.Mask" "F.Paste")
			(roundrect_rratio 0.25)
			(net 1 "GND")
			(pintype "passive")
		)
		(pad "2" smd roundrect
			(at 0.48 0)
			(size 0.59 0.64)
			(layers "F.Cu" "F.Mask" "F.Paste")
			(roundrect_rratio 0.25)
			(net 24 "+3V3")
			(pintype "passive")
		)
	)
	(footprint "antmicro-footprints:USB-C_Receptacle_GCT_USB4105-GF-A"
		(locked yes)
		(layer "F.Cu")
		(at 267.11 127 90)
		(property "Reference" "J14"
			(at 5.3 -1.31 180)
			(layer "F.SilkS")
			(effects
				(font
					(size 0.7 0.7)
					(thickness 0.15)
				)
				(justify left bottom)
			)
		)
		(property "Value" "USB-C_GCT_USB4105-GF-A"
			(at 0 5 90)
			(layer "F.Fab")
			(effects
				(font
					(size 0.7 0.7)
					(thickness 0.15)
				)
				(justify left bottom)
			)
		)
		(property "Description" "USB-C (USB TYPE-C) USB 2.0 Receptacle Connector 24 (16+8 Dummy) Position Surface Mount, Right Angle"
			(at 0 0 90)
			(layer "F.Fab")
			(hide yes)
			(effects
				(font
					(size 1.27 1.27)
					(thickness 0.15)
				)
			)
		)
		(property "Author" "Antmicro"
			(at 394.11 -140.11 0)
			(layer "F.Fab")
			(hide yes)
			(effects
				(font
					(size 1 1)
					(thickness 0.15)
				)
			)
		)
		(property "License" "Apache-2.0"
			(at 394.11 -140.11 0)
			(layer "F.Fab")
			(hide yes)
			(effects
				(font
					(size 1 1)
					(thickness 0.15)
				)
			)
		)
		(property "MPN" "USB4105-GF-A"
			(at 394.11 -140.11 0)
			(layer "F.Fab")
			(hide yes)
			(effects
				(font
					(size 1 1)
					(thickness 0.15)
				)
			)
		)
		(property "Manufacturer" "GCT"
			(at 394.11 -140.11 0)
			(layer "F.Fab")
			(hide yes)
			(effects
				(font
					(size 1 1)
					(thickness 0.15)
				)
			)
		)
		(property "VSD_Class" "USB-C"
			(at 394.11 -140.11 0)
			(layer "F.Fab")
			(hide yes)
			(effects
				(font
					(size 1 1)
					(thickness 0.15)
				)
			)
		)
		(sheetname "USB PHY")
		(sheetfile "usb-phy.kicad_sch")
		(attr smd)
		(fp_line
			(start 4.788 -1.395)
			(end 4.788 -0.145)
			(stroke
				(width 0.15)
				(type solid)
			)
			(layer "F.SilkS")
		)
		(fp_line
			(start -4.79 -1.395)
			(end -4.79 -0.145)
			(stroke
				(width 0.15)
				(type solid)
			)
			(layer "F.SilkS")
		)
		(fp_line
			(start -4.79 2.575)
			(end -4.79 3.854)
			(stroke
				(width 0.15)
				(type solid)
			)
			(layer "F.SilkS")
		)
		(fp_line
			(start 4.788 3.854)
			(end 4.788 2.575)
			(stroke
				(width 0.15)
				(type solid)
			)
			(layer "F.SilkS")
		)
		(fp_line
			(start -4.79 3.854)
			(end 4.788 3.854)
			(stroke
				(width 0.15)
				(type solid)
			)
			(layer "F.SilkS")
		)
		(fp_circle
			(center -3.8 -4.27071)
			(end -3.75 -4.22071)
			(stroke
				(width 0.15)
				(type solid)
			)
			(fill yes)
			(layer "F.SilkS")
		)
		(fp_rect
			(start -5.1 -4.4)
			(end 5.1 3.9)
			(stroke
				(width 0.05)
				(type solid)
			)
			(fill no)
			(layer "F.CrtYd")
		)
		(fp_line
			(start 4.788 -3.676)
			(end 4.788 3.854)
			(stroke
				(width 0.15)
				(type solid)
			)
			(layer "F.Fab")
		)
		(fp_line
			(start -4.79 -3.676)
			(end 4.788 -3.676)
			(stroke
				(width 0.15)
				(type solid)
			)
			(layer "F.Fab")
		)
		(fp_line
			(start 4.788 3.854)
			(end -4.79 3.854)
			(stroke
				(width 0.15)
				(type solid)
			)
			(layer "F.Fab")
		)
		(fp_line
			(start -4.702 3.854)
			(end 4.788 3.854)
			(stroke
				(width 0.15)
				(type solid)
			)
			(layer "F.Fab")
		)
		(fp_line
			(start -4.79 3.854)
			(end -4.79 -3.676)
			(stroke
				(width 0.15)
				(type solid)
			)
			(layer "F.Fab")
		)
		(pad "" np_thru_hole circle
			(at -2.891 -2.426 90)
			(size 0.65 0.65)
			(drill 0.65)
			(layers "*.Cu" "*.Mask")
		)
		(pad "" np_thru_hole circle
			(at 2.89 -2.426 90)
			(size 0.65 0.65)
			(drill 0.65)
			(layers "*.Cu" "*.Mask")
		)
		(pad "A1" smd roundrect
			(at -3.202 -3.5 90)
			(size 0.6 1.15)
			(layers "F.Cu" "F.Mask" "F.Paste")
			(roundrect_rratio 0.25)
			(net 1 "GND")
			(pinfunction "GND")
			(pintype "power_in")
		)
		(pad "A4" smd roundrect
			(at -2.4 -3.5 90)
			(size 0.6 1.15)
			(layers "F.Cu" "F.Mask" "F.Paste")
			(roundrect_rratio 0.25)
			(net 715 "/USB PHY/USB_USR_VBUS")
			(pinfunction "VBUS")
			(pintype "passive")
		)
		(pad "A5" smd roundrect
			(at -1.25 -3.5 90)
			(size 0.3 1.15)
			(layers "F.Cu" "F.Mask" "F.Paste")
			(roundrect_rratio 0.25)
			(net 841 "/USB PHY/USB_USR_CC1")
			(pinfunction "CC_{1}")
			(pintype "bidirectional")
		)
		(pad "A6" smd roundrect
			(at -0.25 -3.5 90)
			(size 0.3 1.15)
			(layers "F.Cu" "F.Mask" "F.Paste")
			(roundrect_rratio 0.25)
			(net 842 "/USB PHY/USB_USR_CONN_D+")
			(pinfunction "D_{A}+")
			(pintype "bidirectional")
		)
		(pad "A7" smd roundrect
			(at 0.248 -3.5 90)
			(size 0.3 1.15)
			(layers "F.Cu" "F.Mask" "F.Paste")
			(roundrect_rratio 0.25)
			(net 843 "/USB PHY/USB_USR_CONN_D-")
			(pinfunction "D_{A}-")
			(pintype "bidirectional")
		)
		(pad "A8" smd roundrect
			(at 1.249 -3.5 90)
			(size 0.3 1.15)
			(layers "F.Cu" "F.Mask" "F.Paste")
			(roundrect_rratio 0.25)
			(net 34 "unconnected-(J14-SBU_{1}-PadA8)")
			(pinfunction "SBU_{1}")
			(pintype "bidirectional+no_connect")
		)
		(pad "A9" smd roundrect
			(at 2.398 -3.5 90)
			(size 0.6 1.15)
			(layers "F.Cu" "F.Mask" "F.Paste")
			(roundrect_rratio 0.25)
			(net 715 "/USB PHY/USB_USR_VBUS")
			(pinfunction "VBUS")
			(pintype "passive")
		)
		(pad "A12" smd roundrect
			(at 3.2 -3.5 90)
			(size 0.6 1.15)
			(layers "F.Cu" "F.Mask" "F.Paste")
			(roundrect_rratio 0.25)
			(net 1 "GND")
			(pinfunction "GND")
			(pintype "passive")
		)
		(pad "B1" smd roundrect
			(at 3.2 -3.5 90)
			(size 0.6 1.15)
			(layers "F.Cu" "F.Mask" "F.Paste")
			(roundrect_rratio 0.25)
			(net 1 "GND")
			(pinfunction "GND")
			(pintype "passive")
		)
		(pad "B4" smd roundrect
			(at 2.398 -3.5 90)
			(size 0.6 1.15)
			(layers "F.Cu" "F.Mask" "F.Paste")
			(roundrect_rratio 0.25)
			(net 715 "/USB PHY/USB_USR_VBUS")
			(pinfunction "VBUS")
			(pintype "passive")
		)
		(pad "B5" smd roundrect
			(at 1.749 -3.5 90)
			(size 0.3 1.15)
			(layers "F.Cu" "F.Mask" "F.Paste")
			(roundrect_rratio 0.25)
			(net 844 "/USB PHY/USB_USR_CC2")
			(pinfunction "CC_{2}")
			(pintype "bidirectional")
		)
		(pad "B6" smd roundrect
			(at 0.748 -3.5 90)
			(size 0.3 1.15)
			(layers "F.Cu" "F.Mask" "F.Paste")
			(roundrect_rratio 0.25)
			(net 842 "/USB PHY/USB_USR_CONN_D+")
			(pinfunction "D_{B}+")
			(pintype "bidirectional")
		)
		(pad "B7" smd roundrect
			(at -0.75 -3.5 90)
			(size 0.3 1.15)
			(layers "F.Cu" "F.Mask" "F.Paste")
			(roundrect_rratio 0.25)
			(net 843 "/USB PHY/USB_USR_CONN_D-")
			(pinfunction "D_{B}-")
			(pintype "bidirectional")
		)
		(pad "B8" smd roundrect
			(at -1.75 -3.5 90)
			(size 0.3 1.15)
			(layers "F.Cu" "F.Mask" "F.Paste")
			(roundrect_rratio 0.25)
			(net 35 "unconnected-(J14-SBU_{2}-PadB8)")
			(pinfunction "SBU_{2}")
			(pintype "bidirectional+no_connect")
		)
		(pad "B9" smd roundrect
			(at -2.4 -3.5 90)
			(size 0.6 1.15)
			(layers "F.Cu" "F.Mask" "F.Paste")
			(roundrect_rratio 0.25)
			(net 715 "/USB PHY/USB_USR_VBUS")
			(pinfunction "VBUS")
			(pintype "passive")
		)
		(pad "B12" smd roundrect
			(at -3.202 -3.5 90)
			(size 0.6 1.15)
			(layers "F.Cu" "F.Mask" "F.Paste")
			(roundrect_rratio 0.25)
			(net 1 "GND")
			(pinfunction "GND")
			(pintype "passive")
		)
		(pad "SH" thru_hole oval
			(at -4.321 -2.926 90)
			(size 1.05 2.1)
			(drill oval 0.6 1.7)
			(layers "*.Cu" "*.Mask")
			(remove_unused_layers no)
			(net 1 "GND")
			(pinfunction "SH")
			(pintype "passive")
		)
		(pad "SH" thru_hole oval
			(at -4.321 1.255 90)
			(size 1 2)
			(drill oval 0.6 1.4)
			(layers "*.Cu" "*.Mask")
			(remove_unused_layers no)
			(net 1 "GND")
			(pinfunction "SH")
			(pintype "passive")
		)
		(pad "SH" thru_hole oval
			(at 4.32 -2.926 90)
			(size 1.05 2.1)
			(drill oval 0.6 1.7)
			(layers "*.Cu" "*.Mask")
			(remove_unused_layers no)
			(net 1 "GND")
			(pinfunction "SH")
			(pintype "passive")
		)
		(pad "SH" thru_hole oval
			(at 4.32 1.255 90)
			(size 1 2)
			(drill oval 0.6 1.4)
			(layers "*.Cu" "*.Mask")
			(remove_unused_layers no)
			(net 1 "GND")
			(pinfunction "SH")
			(pintype "passive")
		)
	)
)
